(kicad_pcb
	(version 20260206)
	(generator "pcbnew")
	(generator_version "10.0")
	(general
		(thickness 1.6)
		(legacy_teardrops no)
	)
	(paper "A4")
	(title_block
		(title "Bryce Canyon_Front Panel_16369-1_OCP.brd")
		(comment 1 "Bryce Canyon / footprints 139-146 of 154")
	)
	(layers
		(0 "F.Cu" signal "TOP")
		(4 "In1.Cu" signal "L2GND")
		(6 "In2.Cu" signal "L3VCC")
		(2 "B.Cu" signal "BOTTOM")
		(9 "F.Adhes" user "F.Adhesive")
		(11 "B.Adhes" user "B.Adhesive")
		(13 "F.Paste" user "Package Geometry/Pastemask Top")
		(15 "B.Paste" user "Package Geometry/Pastemask Bottom")
		(5 "F.SilkS" user "Ref Des/Silkscreen Top")
		(7 "B.SilkS" user "Ref Des/Silkscreen Bottom")
		(1 "F.Mask" user "Board Geometry/Soldermask Top")
		(3 "B.Mask" user "Board Geometry/Soldermask Bottom")
		(17 "Dwgs.User" user "User.Drawings")
		(19 "Cmts.User" user "User.Comments")
		(21 "Eco1.User" user "User.Eco1")
		(23 "Eco2.User" user "User.Eco2")
		(25 "Edge.Cuts" user "Board Geometry/Outline")
		(27 "Margin" user)
		(31 "F.CrtYd" user "Package Geometry/Place Bound Top")
		(29 "B.CrtYd" user "Package Geometry/Place Bound Bottom")
		(35 "F.Fab" user "Ref Des/Assembly Top")
		(33 "B.Fab" user "Ref Des/Assembly Bottom")
	)
	(footprint ""
		(layer "F.Cu")
		(at 55.2196 -46.0502 90)
		(property "Reference" "R37"
			(at 0 0 90)
			(layer "F.SilkS")
			(hide yes)
			(effects
				(font
					(size 1.27 1.27)
				)
			)
		)
		(property "Value" "4K7R2F-GP"
			(at 0.064008 -4.679696 90)
			(unlocked yes)
			(layer "F.Fab")
			(hide yes)
			(effects
				(font
					(size 2.54 2.54)
					(thickness 0.381)
				)
			)
		)
		(property "Device Type" "R402H16"
			(at 0.064008 -6.203696 90)
			(unlocked yes)
			(layer "F.Fab")
			(hide yes)
			(effects
				(font
					(size 2.54 2.54)
					(thickness 0.381)
				)
			)
		)
		(duplicate_pad_numbers_are_jumpers no)
		(fp_line
			(start 0.508 -0.9398)
			(end -0.508 -0.9398)
			(stroke
				(width 0.1524)
				(type default)
			)
			(layer "F.SilkS")
		)
		(fp_line
			(start -0.508 -0.9398)
			(end -0.508 0.9398)
			(stroke
				(width 0.1524)
				(type default)
			)
			(layer "F.SilkS")
		)
		(fp_rect
			(start -0.508 0.9398)
			(end 0.508 -0.9398)
			(stroke
				(width 0)
				(type default)
			)
			(fill no)
			(layer "F.CrtYd")
		)
		(fp_rect
			(start -0.508 0.9398)
			(end 0.508 -0.9398)
			(stroke
				(width 0)
				(type default)
			)
			(fill no)
			(layer "F.Fab")
		)
		(pad "1" smd custom
			(at 0 -0.4445 90)
			(size 0.1397 0.1397)
			(layers "F.Cu" "F.Mask" "F.Paste")
			(net "TEMP_2_A2")
			(options
				(clearance outline)
				(anchor circle)
			)
			(primitives
				(gr_poly
					(pts
						(arc
							(start -0.1778 -0.2794)
							(mid -0.249642 -0.249642)
							(end -0.2794 -0.1778)
						)
						(arc
							(start -0.2794 0.1778)
							(mid -0.249642 0.249642)
							(end -0.1778 0.2794)
						)
						(arc
							(start 0.1778 0.2794)
							(mid 0.249642 0.249642)
							(end 0.2794 0.1778)
						)
						(arc
							(start 0.2794 -0.1778)
							(mid 0.249642 -0.249642)
							(end 0.1778 -0.2794)
						)
					)
					(width 0)
					(fill yes)
				)
			)
		)
		(pad "2" smd custom
			(at 0 0.4445 90)
			(size 0.1397 0.1397)
			(layers "F.Cu" "F.Mask" "F.Paste")
			(net "GND")
			(options
				(clearance outline)
				(anchor circle)
			)
			(primitives
				(gr_poly
					(pts
						(arc
							(start -0.1778 -0.2794)
							(mid -0.249642 -0.249642)
							(end -0.2794 -0.1778)
						)
						(arc
							(start -0.2794 0.1778)
							(mid -0.249642 0.249642)
							(end -0.1778 0.2794)
						)
						(arc
							(start 0.1778 0.2794)
							(mid 0.249642 0.249642)
							(end 0.2794 0.1778)
						)
						(arc
							(start 0.2794 -0.1778)
							(mid 0.249642 -0.249642)
							(end 0.1778 -0.2794)
						)
					)
					(width 0)
					(fill yes)
				)
			)
		)
	)
	(footprint ""
		(layer "F.Cu")
		(at 55.621428 -12.481306 90)
		(property "Reference" "R10"
			(at 0 0 90)
			(layer "F.SilkS")
			(hide yes)
			(effects
				(font
					(size 1.27 1.27)
				)
			)
		)
		(property "Value" "0R2J-2-GP"
			(at 0.064008 -4.679696 90)
			(unlocked yes)
			(layer "F.Fab")
			(hide yes)
			(effects
				(font
					(size 2.54 2.54)
					(thickness 0.381)
				)
			)
		)
		(property "Device Type" "R402H16"
			(at 0.064008 -6.203696 90)
			(unlocked yes)
			(layer "F.Fab")
			(hide yes)
			(effects
				(font
					(size 2.54 2.54)
					(thickness 0.381)
				)
			)
		)
		(duplicate_pad_numbers_are_jumpers no)
		(fp_line
			(start 0.508 -0.9398)
			(end -0.508 -0.9398)
			(stroke
				(width 0.1524)
				(type default)
			)
			(layer "F.SilkS")
		)
		(fp_line
			(start -0.508 -0.9398)
			(end -0.508 0.9398)
			(stroke
				(width 0.1524)
				(type default)
			)
			(layer "F.SilkS")
		)
		(fp_rect
			(start -0.508 0.9398)
			(end 0.508 -0.9398)
			(stroke
				(width 0)
				(type default)
			)
			(fill no)
			(layer "F.CrtYd")
		)
		(fp_rect
			(start -0.508 0.9398)
			(end 0.508 -0.9398)
			(stroke
				(width 0)
				(type default)
			)
			(fill no)
			(layer "F.Fab")
		)
		(pad "1" smd custom
			(at 0 -0.4445 90)
			(size 0.1397 0.1397)
			(layers "F.Cu" "F.Mask" "F.Paste")
			(net "UART_SEL_B_MUX_R")
			(options
				(clearance outline)
				(anchor circle)
			)
			(primitives
				(gr_poly
					(pts
						(arc
							(start -0.1778 -0.2794)
							(mid -0.249642 -0.249642)
							(end -0.2794 -0.1778)
						)
						(arc
							(start -0.2794 0.1778)
							(mid -0.249642 0.249642)
							(end -0.1778 0.2794)
						)
						(arc
							(start 0.1778 0.2794)
							(mid 0.249642 0.249642)
							(end 0.2794 0.1778)
						)
						(arc
							(start 0.2794 -0.1778)
							(mid 0.249642 -0.249642)
							(end 0.1778 -0.2794)
						)
					)
					(width 0)
					(fill yes)
				)
			)
		)
		(pad "2" smd custom
			(at 0 0.4445 90)
			(size 0.1397 0.1397)
			(layers "F.Cu" "F.Mask" "F.Paste")
			(net "GND")
			(options
				(clearance outline)
				(anchor circle)
			)
			(primitives
				(gr_poly
					(pts
						(arc
							(start -0.1778 -0.2794)
							(mid -0.249642 -0.249642)
							(end -0.2794 -0.1778)
						)
						(arc
							(start -0.2794 0.1778)
							(mid -0.249642 0.249642)
							(end -0.1778 0.2794)
						)
						(arc
							(start 0.1778 0.2794)
							(mid 0.249642 0.249642)
							(end 0.2794 0.1778)
						)
						(arc
							(start 0.2794 -0.1778)
							(mid 0.249642 -0.249642)
							(end 0.1778 -0.2794)
						)
					)
					(width 0)
					(fill yes)
				)
			)
		)
	)
	(footprint ""
		(layer "F.Cu")
		(at 20.1168 -16.3322)
		(property "Reference" "R66"
			(at 0 0 0)
			(layer "F.SilkS")
			(hide yes)
			(effects
				(font
					(size 1.27 1.27)
				)
			)
		)
		(property "Value" "4K7R2F-GP"
			(at 0.064008 -3.993896 0)
			(unlocked yes)
			(layer "F.Fab")
			(hide yes)
			(effects
				(font
					(size 1.016 1.016)
					(thickness 0.1524)
				)
			)
		)
		(property "Device Type" "R402H16"
			(at 0.064008 -5.517896 0)
			(unlocked yes)
			(layer "F.Fab")
			(hide yes)
			(effects
				(font
					(size 1.016 1.016)
					(thickness 0.1524)
				)
			)
		)
		(duplicate_pad_numbers_are_jumpers no)
		(fp_line
			(start -0.508 -0.9398)
			(end -0.508 0.9398)
			(stroke
				(width 0.1524)
				(type default)
			)
			(layer "F.SilkS")
		)
		(fp_line
			(start 0.508 -0.9398)
			(end -0.508 -0.9398)
			(stroke
				(width 0.1524)
				(type default)
			)
			(layer "F.SilkS")
		)
		(fp_rect
			(start -0.508 0.9398)
			(end 0.508 -0.9398)
			(stroke
				(width 0)
				(type default)
			)
			(fill no)
			(layer "F.CrtYd")
		)
		(fp_rect
			(start -0.508 0.9398)
			(end 0.508 -0.9398)
			(stroke
				(width 0)
				(type default)
			)
			(fill no)
			(layer "F.Fab")
		)
		(pad "1" smd custom
			(at 0 -0.4445)
			(size 0.1397 0.1397)
			(layers "F.Cu" "F.Mask" "F.Paste")
			(net "TCA9555_A_A1")
			(options
				(clearance outline)
				(anchor circle)
			)
			(primitives
				(gr_poly
					(pts
						(arc
							(start -0.1778 -0.2794)
							(mid -0.249642 -0.249642)
							(end -0.2794 -0.1778)
						)
						(arc
							(start -0.2794 0.1778)
							(mid -0.249642 0.249642)
							(end -0.1778 0.2794)
						)
						(arc
							(start 0.1778 0.2794)
							(mid 0.249642 0.249642)
							(end 0.2794 0.1778)
						)
						(arc
							(start 0.2794 -0.1778)
							(mid 0.249642 -0.249642)
							(end 0.1778 -0.2794)
						)
					)
					(width 0)
					(fill yes)
				)
			)
		)
		(pad "2" smd custom
			(at 0 0.4445)
			(size 0.1397 0.1397)
			(layers "F.Cu" "F.Mask" "F.Paste")
			(net "GND")
			(options
				(clearance outline)
				(anchor circle)
			)
			(primitives
				(gr_poly
					(pts
						(arc
							(start -0.1778 -0.2794)
							(mid -0.249642 -0.249642)
							(end -0.2794 -0.1778)
						)
						(arc
							(start -0.2794 0.1778)
							(mid -0.249642 0.249642)
							(end -0.1778 0.2794)
						)
						(arc
							(start 0.1778 0.2794)
							(mid 0.249642 0.249642)
							(end 0.2794 0.1778)
						)
						(arc
							(start 0.2794 -0.1778)
							(mid 0.249642 -0.249642)
							(end 0.1778 -0.2794)
						)
					)
					(width 0)
					(fill yes)
				)
			)
		)
	)
	(footprint ""
		(layer "F.Cu")
		(at 46.647862 -48.528732)
		(property "Reference" "TP8"
			(at 0 0 0)
			(layer "F.SilkS")
			(hide yes)
			(effects
				(font
					(size 1.27 1.27)
				)
			)
		)
		(property "Value" "TPAD32-GP"
			(at -0.0508 -1.6764 0)
			(unlocked yes)
			(layer "F.Fab")
			(hide yes)
			(effects
				(font
					(size 1.016 1.016)
					(thickness 0.1524)
				)
			)
		)
		(property "Device Type" "TPAD32"
			(at -0.0508 -3.2004 0)
			(unlocked yes)
			(layer "F.Fab")
			(hide yes)
			(effects
				(font
					(size 1.016 1.016)
					(thickness 0.1524)
				)
			)
		)
		(duplicate_pad_numbers_are_jumpers no)
		(fp_poly
			(pts
				(arc
					(start 0.4064 0)
					(mid -0.4064 0)
					(end 0.4064 0)
				)
			)
			(stroke
				(width 0)
				(type default)
			)
			(fill no)
			(layer "F.CrtYd")
		)
		(fp_poly
			(pts
				(arc
					(start 0.7112 0)
					(mid -0.7112 0)
					(end 0.7112 0)
				)
			)
			(stroke
				(width 0)
				(type default)
			)
			(fill no)
			(layer "F.Fab")
		)
		(pad "1" smd circle
			(at 0 0)
			(size 0.8128 0.8128)
			(layers "F.Cu" "F.Mask" "F.Paste")
			(net "TEMP_2_ALERT")
		)
	)
	(footprint ""
		(layer "F.Cu")
		(at 42.342308 -9.672828 90)
		(property "Reference" "U13"
			(at 0 0 90)
			(layer "F.SilkS")
			(hide yes)
			(effects
				(font
					(size 1.27 1.27)
				)
			)
		)
		(property "Value" "SNLVC1G126DCKR-GP"
			(at -2.3368 -8.6868 90)
			(unlocked yes)
			(layer "F.Fab")
			(hide yes)
			(effects
				(font
					(size 1.016 1.016)
					(thickness 0.1524)
				)
			)
		)
		(property "Device Type" "SC70-5H44"
			(at -2.3114 -10.414 90)
			(unlocked yes)
			(layer "F.Fab")
			(hide yes)
			(effects
				(font
					(size 1.016 1.016)
					(thickness 0.1524)
				)
			)
		)
		(duplicate_pad_numbers_are_jumpers no)
		(fp_line
			(start 1.3843 -1.8034)
			(end 1.3843 -1.1176)
			(stroke
				(width 0.3302)
				(type default)
			)
			(layer "F.SilkS")
		)
		(fp_line
			(start 0.6604 -1.8034)
			(end 1.3843 -1.8034)
			(stroke
				(width 0.3302)
				(type default)
			)
			(layer "F.SilkS")
		)
		(fp_line
			(start 1.27 -1.7018)
			(end 1.27 1.7018)
			(stroke
				(width 0.1524)
				(type default)
			)
			(layer "F.SilkS")
		)
		(fp_line
			(start -1.27 -1.7018)
			(end 1.27 -1.7018)
			(stroke
				(width 0.1524)
				(type default)
			)
			(layer "F.SilkS")
		)
		(fp_line
			(start 1.27 1.7018)
			(end -1.27 1.7018)
			(stroke
				(width 0.1524)
				(type default)
			)
			(layer "F.SilkS")
		)
		(fp_line
			(start -1.27 1.7018)
			(end -1.27 -1.7018)
			(stroke
				(width 0.1524)
				(type default)
			)
			(layer "F.SilkS")
		)
		(fp_rect
			(start -1.524 1.9558)
			(end 1.524 -1.9558)
			(stroke
				(width 0)
				(type default)
			)
			(fill no)
			(layer "F.CrtYd")
		)
		(fp_poly
			(pts
				(xy -1.524 -1.9558) (xy 1.524 -1.9558) (xy 1.524 1.9558) (xy -1.524 1.9558)
			)
			(stroke
				(width 0)
				(type default)
			)
			(fill no)
			(layer "F.Fab")
		)
		(pad "1" smd rect
			(at 0.65024 -0.8255 90)
			(size 0.4064 1.2192)
			(layers "F.Cu" "F.Mask" "F.Paste")
			(net "DEBUG_CARD_B_PRSNT")
		)
		(pad "2" smd rect
			(at 0 -0.8255 90)
			(size 0.4064 1.2192)
			(layers "F.Cu" "F.Mask" "F.Paste")
			(net "UART_B_TX")
		)
		(pad "3" smd rect
			(at -0.65024 -0.8255 90)
			(size 0.4064 1.2192)
			(layers "F.Cu" "F.Mask" "F.Paste")
			(net "GND")
		)
		(pad "4" smd rect
			(at -0.65024 0.8255 90)
			(size 0.4064 1.2192)
			(layers "F.Cu" "F.Mask" "F.Paste")
			(net "UART_DEBUG_B_TX")
		)
		(pad "5" smd rect
			(at 0.65024 0.8255 90)
			(size 0.4064 1.2192)
			(layers "F.Cu" "F.Mask" "F.Paste")
			(net "P3V3_STBY_B")
		)
	)
	(footprint ""
		(layer "F.Cu")
		(at 4.977892 -39.310818 90)
		(property "Reference" "C11"
			(at 0 0 90)
			(layer "F.SilkS")
			(hide yes)
			(effects
				(font
					(size 1.27 1.27)
				)
			)
		)
		(property "Value" "SC1U16V3KX-5GP"
			(at 0 -3.5052 90)
			(unlocked yes)
			(layer "F.Fab")
			(hide yes)
			(effects
				(font
					(size 2.54 2.54)
					(thickness 0.381)
				)
			)
		)
		(property "Device Type" "C603H36"
			(at 0 -5.0292 90)
			(unlocked yes)
			(layer "F.Fab")
			(hide yes)
			(effects
				(font
					(size 2.54 2.54)
					(thickness 0.381)
				)
			)
		)
		(duplicate_pad_numbers_are_jumpers no)
		(fp_line
			(start 0.508 0)
			(end -0.508 0)
			(stroke
				(width 0.2032)
				(type default)
			)
			(layer "F.SilkS")
		)
		(fp_rect
			(start -0.5842 1.3335)
			(end 0.5842 -1.3335)
			(stroke
				(width 0)
				(type default)
			)
			(fill no)
			(layer "F.CrtYd")
		)
		(fp_rect
			(start -0.5842 1.3335)
			(end 0.5842 -1.3335)
			(stroke
				(width 0)
				(type default)
			)
			(fill no)
			(layer "F.Fab")
		)
		(pad "1" smd custom
			(at 0 -0.762 90)
			(size 0.2159 0.2159)
			(layers "F.Cu" "F.Mask" "F.Paste")
			(net "SYS_RESET_BTN_A")
			(options
				(clearance outline)
				(anchor circle)
			)
			(primitives
				(gr_poly
					(pts
						(arc
							(start -0.3302 -0.4318)
							(mid -0.402042 -0.402042)
							(end -0.4318 -0.3302)
						)
						(arc
							(start -0.4318 0.3302)
							(mid -0.402042 0.402042)
							(end -0.3302 0.4318)
						)
						(arc
							(start 0.3302 0.4318)
							(mid 0.402042 0.402042)
							(end 0.4318 0.3302)
						)
						(arc
							(start 0.4318 -0.3302)
							(mid 0.402042 -0.402042)
							(end 0.3302 -0.4318)
						)
					)
					(width 0)
					(fill yes)
				)
			)
		)
		(pad "2" smd custom
			(at 0 0.762 90)
			(size 0.2159 0.2159)
			(layers "F.Cu" "F.Mask" "F.Paste")
			(net "GND")
			(options
				(clearance outline)
				(anchor circle)
			)
			(primitives
				(gr_poly
					(pts
						(arc
							(start -0.3302 -0.4318)
							(mid -0.402042 -0.402042)
							(end -0.4318 -0.3302)
						)
						(arc
							(start -0.4318 0.3302)
							(mid -0.402042 0.402042)
							(end -0.3302 0.4318)
						)
						(arc
							(start 0.3302 0.4318)
							(mid 0.402042 0.402042)
							(end 0.4318 0.3302)
						)
						(arc
							(start 0.4318 -0.3302)
							(mid 0.402042 -0.402042)
							(end 0.3302 -0.4318)
						)
					)
					(width 0)
					(fill yes)
				)
			)
		)
	)
	(footprint ""
		(layer "F.Cu")
		(at 13.3604 -6.4262)
		(property "Reference" "C21"
			(at 0 0 0)
			(layer "F.SilkS")
			(hide yes)
			(effects
				(font
					(size 1.27 1.27)
				)
			)
		)
		(property "Value" "SCD1U16V2KX-3GP"
			(at 1.1811 -2.7051 0)
			(unlocked yes)
			(layer "F.Fab")
			(hide yes)
			(effects
				(font
					(size 1.016 1.016)
					(thickness 0.1524)
				)
			)
		)
		(property "Device Type" "C402H22"
			(at 1.1811 -4.2291 0)
			(unlocked yes)
			(layer "F.Fab")
			(hide yes)
			(effects
				(font
					(size 1.016 1.016)
					(thickness 0.1524)
				)
			)
		)
		(duplicate_pad_numbers_are_jumpers no)
		(fp_rect
			(start -0.4318 0.9525)
			(end 0.4318 -0.9525)
			(stroke
				(width 0)
				(type default)
			)
			(fill no)
			(layer "F.CrtYd")
		)
		(fp_rect
			(start -0.4318 0.9525)
			(end 0.4318 -0.9525)
			(stroke
				(width 0)
				(type default)
			)
			(fill no)
			(layer "F.Fab")
		)
		(pad "1" smd custom
			(at 0 -0.4445)
			(size 0.1524 0.1524)
			(layers "F.Cu" "F.Mask" "F.Paste")
			(net "P3V3_STBY_A")
			(options
				(clearance outline)
				(anchor circle)
			)
			(primitives
				(gr_poly
					(pts
						(arc
							(start 0.3048 -0.2032)
							(mid 0.275042 -0.275042)
							(end 0.2032 -0.3048)
						)
						(arc
							(start -0.2032 -0.3048)
							(mid -0.275042 -0.275042)
							(end -0.3048 -0.2032)
						)
						(arc
							(start -0.3048 0.2032)
							(mid -0.275042 0.275042)
							(end -0.2032 0.3048)
						)
						(arc
							(start 0.2032 0.3048)
							(mid 0.275042 0.275042)
							(end 0.3048 0.2032)
						)
					)
					(width 0)
					(fill yes)
				)
			)
		)
		(pad "2" smd custom
			(at 0 0.4445)
			(size 0.1524 0.1524)
			(layers "F.Cu" "F.Mask" "F.Paste")
			(net "GND")
			(options
				(clearance outline)
				(anchor circle)
			)
			(primitives
				(gr_poly
					(pts
						(arc
							(start 0.3048 -0.2032)
							(mid 0.275042 -0.275042)
							(end 0.2032 -0.3048)
						)
						(arc
							(start -0.2032 -0.3048)
							(mid -0.275042 -0.275042)
							(end -0.3048 -0.2032)
						)
						(arc
							(start -0.3048 0.2032)
							(mid -0.275042 0.275042)
							(end -0.2032 0.3048)
						)
						(arc
							(start 0.2032 0.3048)
							(mid 0.275042 0.275042)
							(end 0.3048 0.2032)
						)
					)
					(width 0)
					(fill yes)
				)
			)
		)
	)
	(footprint ""
		(layer "F.Cu")
		(at 4.0386 -21.4884 180)
		(property "Reference" "C20"
			(at 0 0 180)
			(layer "F.SilkS")
			(hide yes)
			(effects
				(font
					(size 1.27 1.27)
				)
			)
		)
		(property "Value" "SCD1U16V2KX-3GP"
			(at 1.1811 -2.7051 180)
			(unlocked yes)
			(layer "F.Fab")
			(hide yes)
			(effects
				(font
					(size 1.016 1.016)
					(thickness 0.1524)
				)
			)
		)
		(property "Device Type" "C402H22"
			(at 1.1811 -4.2291 180)
			(unlocked yes)
			(layer "F.Fab")
			(hide yes)
			(effects
				(font
					(size 1.016 1.016)
					(thickness 0.1524)
				)
			)
		)
		(duplicate_pad_numbers_are_jumpers no)
		(fp_rect
			(start -0.4318 0.9525)
			(end 0.4318 -0.9525)
			(stroke
				(width 0)
				(type default)
			)
			(fill no)
			(layer "F.CrtYd")
		)
		(fp_rect
			(start -0.4318 0.9525)
			(end 0.4318 -0.9525)
			(stroke
				(width 0)
				(type default)
			)
			(fill no)
			(layer "F.Fab")
		)
		(pad "1" smd custom
			(at 0 -0.4445 180)
			(size 0.1524 0.1524)
			(layers "F.Cu" "F.Mask" "F.Paste")
			(net "P3V3_STBY_A")
			(options
				(clearance outline)
				(anchor circle)
			)
			(primitives
				(gr_poly
					(pts
						(arc
							(start 0.3048 -0.2032)
							(mid 0.275042 -0.275042)
							(end 0.2032 -0.3048)
						)
						(arc
							(start -0.2032 -0.3048)
							(mid -0.275042 -0.275042)
							(end -0.3048 -0.2032)
						)
						(arc
							(start -0.3048 0.2032)
							(mid -0.275042 0.275042)
							(end -0.2032 0.3048)
						)
						(arc
							(start 0.2032 0.3048)
							(mid 0.275042 0.275042)
							(end 0.3048 0.2032)
						)
					)
					(width 0)
					(fill yes)
				)
			)
		)
		(pad "2" smd custom
			(at 0 0.4445 180)
			(size 0.1524 0.1524)
			(layers "F.Cu" "F.Mask" "F.Paste")
			(net "GND")
			(options
				(clearance outline)
				(anchor circle)
			)
			(primitives
				(gr_poly
					(pts
						(arc
							(start 0.3048 -0.2032)
							(mid 0.275042 -0.275042)
							(end 0.2032 -0.3048)
						)
						(arc
							(start -0.2032 -0.3048)
							(mid -0.275042 -0.275042)
							(end -0.3048 -0.2032)
						)
						(arc
							(start -0.3048 0.2032)
							(mid -0.275042 0.275042)
							(end -0.2032 0.3048)
						)
						(arc
							(start 0.2032 0.3048)
							(mid 0.275042 0.275042)
							(end 0.3048 0.2032)
						)
					)
					(width 0)
					(fill yes)
				)
			)
		)
	)
)
